FILE_TYPE = CONNECTIVITY;
{Allegro Design Entry HDL 16.6-p007 (v16-6-112F) 10/10/2012}
"PAGE_NUMBER" = 6;
0"NC";
END.
